# S9S_MB_2U (Grand Teton) — schematic netlist excerpt (pin names and nets, part order shuffled) for the footprints in the layout excerpt that follows; sources: Cadence DE-HDL packaged netlist, KiCad conversion of 03242023_DA0F0TMBIJ0_F0T_Motherboard_J_brd_V01_OCP.brd

R3168  Q_RES  0 5% CHIP  pkg 0402LF  page 159 : A = OCP_V3_2_MAIN_PWR_EN ; B = OCP_V3_2_MAIN_PWR_EN_R
R435  Q_RES  33.2 1% CHIP  pkg 0402LF  page 155 : A = RST_OCP_V3_1_BUF_N ; B = RST_PERST1_OCP_SFF_N
PC516_P1_5  Q_CAP  22UF 16V 20% X6S  pkg C0805  page 287 : A = SW_P12V_PVCCIN_CPU1_FLT ; B = GND

(kicad_pcb
	(version 20260206)
	(generator "pcbnew")
	(generator_version "10.0")
	(general
		(thickness 1.6)
		(legacy_teardrops no)
	)
	(paper "A4")
	(title_block
		(title "03242023_DA0F0TMBIJ0_F0T_Motherboard_J_brd_V01_OCP.brd")
		(comment 1 "Grand Teton / footprints 5137-5139 of 6105")
	)
	(layers
		(0 "F.Cu" signal "TOP")
		(4 "In1.Cu" signal "GND")
		(6 "In2.Cu" signal "IN1")
		(8 "In3.Cu" signal "GND1")
		(10 "In4.Cu" signal "IN2")
		(12 "In5.Cu" signal "GND2")
		(14 "In6.Cu" signal "IN3")
		(16 "In7.Cu" signal "GND3")
		(18 "In8.Cu" signal "VCC")
		(20 "In9.Cu" signal "VCC1")
		(22 "In10.Cu" signal "GND4")
		(24 "In11.Cu" signal "IN4")
		(26 "In12.Cu" signal "GND5")
		(28 "In13.Cu" signal "IN5")
		(30 "In14.Cu" signal "GND6")
		(32 "In15.Cu" signal "IN6")
		(34 "In16.Cu" signal "GND7")
		(2 "B.Cu" signal "BOTTOM")
		(9 "F.Adhes" user "F.Adhesive")
		(11 "B.Adhes" user "B.Adhesive")
		(13 "F.Paste" user "Package Geometry/Pastemask Top")
		(15 "B.Paste" user "Package Geometry/Pastemask Bottom")
		(5 "F.SilkS" user "Ref Des/Silkscreen Top")
		(7 "B.SilkS" user "Ref Des/Silkscreen Bottom")
		(1 "F.Mask" user "Board Geometry/Soldermask Top")
		(3 "B.Mask" user "Board Geometry/Soldermask Bottom")
		(17 "Dwgs.User" user "User.Drawings")
		(19 "Cmts.User" user "User.Comments")
		(21 "Eco1.User" user "User.Eco1")
		(23 "Eco2.User" user "User.Eco2")
		(25 "Edge.Cuts" user "Board Geometry/Outline")
		(27 "Margin" user)
		(31 "F.CrtYd" user "Package Geometry/Place Bound Top")
		(29 "B.CrtYd" user "Package Geometry/Place Bound Bottom")
		(35 "F.Fab" user "Ref Des/Assembly Top")
		(33 "B.Fab" user "Ref Des/Assembly Bottom")
	)
	(footprint ""
		(layer "B.Cu")
		(at 76.89088 -11.267948 90)
		(property "Reference" "R3168"
			(at 0 0 90)
			(layer "B.SilkS")
			(hide yes)
			(effects
				(font
					(size 1.27 1.27)
				)
				(justify mirror)
			)
		)
		(property "Value" ""
			(at 0 0 90)
			(layer "B.Fab")
			(effects
				(font
					(size 1.27 1.27)
				)
				(justify mirror)
			)
		)
		(duplicate_pad_numbers_are_jumpers no)
		(fp_line
			(start 0.7874 -0.4064)
			(end -0.7874 -0.4064)
			(stroke
				(width 0.1524)
				(type default)
			)
			(layer "B.SilkS")
		)
		(fp_line
			(start -0.7874 -0.4064)
			(end -0.7874 0.4064)
			(stroke
				(width 0.1524)
				(type default)
			)
			(layer "B.SilkS")
		)
		(fp_line
			(start 0.7874 0.4064)
			(end 0.7874 -0.4064)
			(stroke
				(width 0.1524)
				(type default)
			)
			(layer "B.SilkS")
		)
		(fp_line
			(start -0.7874 0.4064)
			(end 0.7874 0.4064)
			(stroke
				(width 0.1524)
				(type default)
			)
			(layer "B.SilkS")
		)
		(fp_line
			(start 0.67945 -0.305054)
			(end 0.12065 -0.305054)
			(stroke
				(width 0.1)
				(type default)
			)
			(layer "B.Fab")
		)
		(fp_line
			(start 0.12065 -0.305054)
			(end 0.12065 -0.2794)
			(stroke
				(width 0.1)
				(type default)
			)
			(layer "B.Fab")
		)
		(fp_line
			(start -0.12065 -0.3048)
			(end -0.67945 -0.3048)
			(stroke
				(width 0.1)
				(type default)
			)
			(layer "B.Fab")
		)
		(fp_line
			(start -0.67945 -0.3048)
			(end -0.67945 0.3048)
			(stroke
				(width 0.1)
				(type default)
			)
			(layer "B.Fab")
		)
		(fp_line
			(start 0.12065 -0.2794)
			(end -0.12065 -0.2794)
			(stroke
				(width 0.1)
				(type default)
			)
			(layer "B.Fab")
		)
		(fp_line
			(start -0.12065 -0.2794)
			(end -0.12065 -0.3048)
			(stroke
				(width 0.1)
				(type default)
			)
			(layer "B.Fab")
		)
		(fp_line
			(start 0.12065 0.2794)
			(end 0.12065 0.3048)
			(stroke
				(width 0.1)
				(type default)
			)
			(layer "B.Fab")
		)
		(fp_line
			(start -0.120396 0.2794)
			(end 0.12065 0.2794)
			(stroke
				(width 0.1)
				(type default)
			)
			(layer "B.Fab")
		)
		(fp_line
			(start 0.67945 0.3048)
			(end 0.67945 -0.305054)
			(stroke
				(width 0.1)
				(type default)
			)
			(layer "B.Fab")
		)
		(fp_line
			(start 0.12065 0.3048)
			(end 0.67945 0.3048)
			(stroke
				(width 0.1)
				(type default)
			)
			(layer "B.Fab")
		)
		(fp_line
			(start -0.120396 0.3048)
			(end -0.120396 0.2794)
			(stroke
				(width 0.1)
				(type default)
			)
			(layer "B.Fab")
		)
		(fp_line
			(start -0.67945 0.3048)
			(end -0.120396 0.3048)
			(stroke
				(width 0.1)
				(type default)
			)
			(layer "B.Fab")
		)
		(pad "1" smd circle
			(at 0.40005 0 270)
			(size 0 0)
			(layers "B.Cu" "B.Mask" "B.Paste")
			(net "OCP_V3_2_MAIN_PWR_EN")
		)
		(pad "2" smd circle
			(at -0.40005 0 270)
			(size 0 0)
			(layers "B.Cu" "B.Mask" "B.Paste")
			(net "OCP_V3_2_MAIN_PWR_EN_R")
		)
	)
	(footprint ""
		(layer "B.Cu")
		(at 434.34635 -5.052568 -90)
		(property "Reference" "R435"
			(at 0 0 90)
			(layer "B.SilkS")
			(hide yes)
			(effects
				(font
					(size 1.27 1.27)
				)
				(justify mirror)
			)
		)
		(property "Value" ""
			(at 0 0 90)
			(layer "B.Fab")
			(effects
				(font
					(size 1.27 1.27)
				)
				(justify mirror)
			)
		)
		(duplicate_pad_numbers_are_jumpers no)
		(fp_line
			(start -0.7874 0.4064)
			(end 0.7874 0.4064)
			(stroke
				(width 0.1524)
				(type default)
			)
			(layer "B.SilkS")
		)
		(fp_line
			(start 0.7874 0.4064)
			(end 0.7874 -0.4064)
			(stroke
				(width 0.1524)
				(type default)
			)
			(layer "B.SilkS")
		)
		(fp_line
			(start -0.7874 -0.4064)
			(end -0.7874 0.4064)
			(stroke
				(width 0.1524)
				(type default)
			)
			(layer "B.SilkS")
		)
		(fp_line
			(start 0.7874 -0.4064)
			(end -0.7874 -0.4064)
			(stroke
				(width 0.1524)
				(type default)
			)
			(layer "B.SilkS")
		)
		(fp_line
			(start -0.67945 0.3048)
			(end -0.120396 0.3048)
			(stroke
				(width 0.1)
				(type default)
			)
			(layer "B.Fab")
		)
		(fp_line
			(start -0.120396 0.3048)
			(end -0.120396 0.2794)
			(stroke
				(width 0.1)
				(type default)
			)
			(layer "B.Fab")
		)
		(fp_line
			(start 0.12065 0.3048)
			(end 0.67945 0.3048)
			(stroke
				(width 0.1)
				(type default)
			)
			(layer "B.Fab")
		)
		(fp_line
			(start 0.67945 0.3048)
			(end 0.67945 -0.305054)
			(stroke
				(width 0.1)
				(type default)
			)
			(layer "B.Fab")
		)
		(fp_line
			(start -0.120396 0.2794)
			(end 0.12065 0.2794)
			(stroke
				(width 0.1)
				(type default)
			)
			(layer "B.Fab")
		)
		(fp_line
			(start 0.12065 0.2794)
			(end 0.12065 0.3048)
			(stroke
				(width 0.1)
				(type default)
			)
			(layer "B.Fab")
		)
		(fp_line
			(start -0.12065 -0.2794)
			(end -0.12065 -0.3048)
			(stroke
				(width 0.1)
				(type default)
			)
			(layer "B.Fab")
		)
		(fp_line
			(start 0.12065 -0.2794)
			(end -0.12065 -0.2794)
			(stroke
				(width 0.1)
				(type default)
			)
			(layer "B.Fab")
		)
		(fp_line
			(start -0.67945 -0.3048)
			(end -0.67945 0.3048)
			(stroke
				(width 0.1)
				(type default)
			)
			(layer "B.Fab")
		)
		(fp_line
			(start -0.12065 -0.3048)
			(end -0.67945 -0.3048)
			(stroke
				(width 0.1)
				(type default)
			)
			(layer "B.Fab")
		)
		(fp_line
			(start 0.12065 -0.305054)
			(end 0.12065 -0.2794)
			(stroke
				(width 0.1)
				(type default)
			)
			(layer "B.Fab")
		)
		(fp_line
			(start 0.67945 -0.305054)
			(end 0.12065 -0.305054)
			(stroke
				(width 0.1)
				(type default)
			)
			(layer "B.Fab")
		)
		(pad "1" smd circle
			(at 0.40005 0 90)
			(size 0 0)
			(layers "B.Cu" "B.Mask" "B.Paste")
			(net "RST_OCP_V3_1_BUF_N")
		)
		(pad "2" smd circle
			(at -0.40005 0 90)
			(size 0 0)
			(layers "B.Cu" "B.Mask" "B.Paste")
			(net "RST_PERST1_OCP_SFF_N")
		)
	)
	(footprint ""
		(layer "B.Cu")
		(at 132.89661 -337.145884 90)
		(property "Reference" "PC516_P1_5"
			(at 0 0 90)
			(layer "B.SilkS")
			(hide yes)
			(effects
				(font
					(size 1.27 1.27)
				)
				(justify mirror)
			)
		)
		(property "Value" ""
			(at 0 0 90)
			(layer "B.Fab")
			(effects
				(font
					(size 1.27 1.27)
				)
				(justify mirror)
			)
		)
		(duplicate_pad_numbers_are_jumpers no)
		(fp_line
			(start 1.524 -0.762)
			(end -1.524 -0.762)
			(stroke
				(width 0.1524)
				(type default)
			)
			(layer "B.SilkS")
		)
		(fp_line
			(start -1.524 -0.762)
			(end -1.524 0.762)
			(stroke
				(width 0.1524)
				(type default)
			)
			(layer "B.SilkS")
		)
		(fp_line
			(start 1.524 0.762)
			(end 1.524 -0.762)
			(stroke
				(width 0.1524)
				(type default)
			)
			(layer "B.SilkS")
		)
		(fp_line
			(start -1.524 0.762)
			(end 1.524 0.762)
			(stroke
				(width 0.1524)
				(type default)
			)
			(layer "B.SilkS")
		)
		(fp_line
			(start 1.1049 -0.724916)
			(end 1.1049 0.724916)
			(stroke
				(width 0.1)
				(type default)
			)
			(layer "B.Fab")
		)
		(fp_line
			(start -1.1049 -0.724916)
			(end 1.1049 -0.724916)
			(stroke
				(width 0.1)
				(type default)
			)
			(layer "B.Fab")
		)
		(fp_line
			(start 1.1049 0.724916)
			(end -1.1049 0.724916)
			(stroke
				(width 0.1)
				(type default)
			)
			(layer "B.Fab")
		)
		(fp_line
			(start -1.1049 0.724916)
			(end -1.1049 -0.724916)
			(stroke
				(width 0.1)
				(type default)
			)
			(layer "B.Fab")
		)
		(pad "1" smd rect
			(at 0.889 0 90)
			(size 1.016 1.27)
			(layers "B.Cu" "B.Mask" "B.Paste")
			(net "SW_P12V_PVCCIN_CPU1_FLT")
		)
		(pad "2" smd rect
			(at -0.889 0 90)
			(size 1.016 1.27)
			(layers "B.Cu" "B.Mask" "B.Paste")
			(net "GND")
		)
	)
)
